(kicad_pcb
	(version 20260206)
	(generator "pcbnew")
	(generator_version "10.0")
	(general
		(thickness 1.6)
		(legacy_teardrops no)
	)
	(paper "A4")
	(title_block
		(title "peb — Lightning_PEB_BRD.brd")
		(comment 1 "Lightning (Wiwynn / Facebook NVMe JBOF) / footprint 1585 of 2563 (U40), pads 114-227 of 408")
	)
	(layers
		(0 "F.Cu" signal "TOP")
		(4 "In1.Cu" signal "L2GND")
		(6 "In2.Cu" signal "L3")
		(8 "In3.Cu" signal "L4VCC")
		(10 "In4.Cu" signal "L5VCC")
		(12 "In5.Cu" signal "L6")
		(14 "In6.Cu" signal "L7GND")
		(2 "B.Cu" signal "BOTTOM")
		(9 "F.Adhes" user "F.Adhesive")
		(11 "B.Adhes" user "B.Adhesive")
		(13 "F.Paste" user "Package Geometry/Pastemask Top")
		(15 "B.Paste" user "Package Geometry/Pastemask Bottom")
		(5 "F.SilkS" user "Ref Des/Silkscreen Top")
		(7 "B.SilkS" user "Ref Des/Silkscreen Bottom")
		(1 "F.Mask" user "Board Geometry/Soldermask Top")
		(3 "B.Mask" user "Board Geometry/Soldermask Bottom")
		(17 "Dwgs.User" user "User.Drawings")
		(19 "Cmts.User" user "User.Comments")
		(21 "Eco1.User" user "User.Eco1")
		(23 "Eco2.User" user "User.Eco2")
		(25 "Edge.Cuts" user "Board Geometry/Outline")
		(27 "Margin" user)
		(31 "F.CrtYd" user "Package Geometry/Place Bound Top")
		(29 "B.CrtYd" user "Package Geometry/Place Bound Bottom")
		(35 "F.Fab" user "Ref Des/Assembly Top")
		(33 "B.Fab" user "Ref Des/Assembly Bottom")
	)
	(footprint ""
		(layer "F.Cu")
		(at 38.104826 -130.48488 180)
		(property "Reference" "U40"
			(at 0 0 180)
			(layer "F.SilkS")
			(hide yes)
			(effects
				(font
					(size 1.27 1.27)
				)
			)
		)
		(property "Value" "AST2400A1-GP"
			(at -17.7292 -6.184392 180)
			(unlocked yes)
			(layer "F.Fab")
			(hide yes)
			(effects
				(font
					(size 1.016 1.016)
					(thickness 0.1524)
				)
			)
		)
		(property "Device Type" "BGA408D19H52"
			(at -17.7292 -7.708392 180)
			(unlocked yes)
			(layer "F.Fab")
			(hide yes)
			(effects
				(font
					(size 1.016 1.016)
					(thickness 0.1524)
				)
			)
		)
		(duplicate_pad_numbers_are_jumpers no)
		(pad "D4" smd circle
			(at -5.999988 -5.999988 180)
			(size 0.3556 0.3556)
			(layers "F.Cu" "F.Mask" "F.Paste")
			(net "BMC0_SCL12_R")
		)
		(pad "D5" smd circle
			(at -5.199888 -5.999988 180)
			(size 0.3556 0.3556)
			(layers "F.Cu" "F.Mask" "F.Paste")
			(net "TP_GPIOA7")
		)
		(pad "D6" smd circle
			(at -4.400042 -5.999988 180)
			(size 0.3556 0.3556)
			(layers "F.Cu" "F.Mask" "F.Paste")
			(net "PEER_TRAY_BMC")
		)
		(pad "D7" smd circle
			(at -3.599942 -5.999988 180)
			(size 0.3556 0.3556)
			(layers "F.Cu" "F.Mask" "F.Paste")
			(net "TP_GPIOH4")
		)
		(pad "D8" smd circle
			(at -2.800096 -5.999988 180)
			(size 0.3556 0.3556)
			(layers "F.Cu" "F.Mask" "F.Paste")
			(net "TP_GPIOV6")
		)
		(pad "D9" smd circle
			(at -1.999996 -5.999988 180)
			(size 0.3556 0.3556)
			(layers "F.Cu" "F.Mask" "F.Paste")
			(net "TP_GPIOT6")
		)
		(pad "D10" smd circle
			(at -1.199896 -5.999988 180)
			(size 0.3556 0.3556)
			(layers "F.Cu" "F.Mask" "F.Paste")
			(net "TP_GPIOU3")
		)
		(pad "D11" smd circle
			(at -0.40005 -5.999988 180)
			(size 0.3556 0.3556)
			(layers "F.Cu" "F.Mask" "F.Paste")
			(net "RMII0_PHY_BMC_RXCTL0")
		)
		(pad "D12" smd circle
			(at 0.40005 -5.999988 180)
			(size 0.3556 0.3556)
			(layers "F.Cu" "F.Mask" "F.Paste")
			(net "RMII0_BMC_C_PHY_TXD1")
		)
		(pad "D13" smd circle
			(at 1.199896 -5.999988 180)
			(size 0.3556 0.3556)
			(layers "F.Cu" "F.Mask" "F.Paste")
			(net "HIGH_HEX_2")
		)
		(pad "D14" smd circle
			(at 1.999996 -5.999988 180)
			(size 0.3556 0.3556)
			(layers "F.Cu" "F.Mask" "F.Paste")
			(net "BMC_ADD2_R")
		)
		(pad "D15" smd circle
			(at 2.800096 -5.999988 180)
			(size 0.3556 0.3556)
			(layers "F.Cu" "F.Mask" "F.Paste")
			(net "FLA1_WPN_R")
		)
		(pad "D16" smd circle
			(at 3.599942 -5.999988 180)
			(size 0.3556 0.3556)
			(layers "F.Cu" "F.Mask" "F.Paste")
			(net "TP_GPIOD1")
		)
		(pad "D17" smd circle
			(at 4.400042 -5.999988 180)
			(size 0.3556 0.3556)
			(layers "F.Cu" "F.Mask" "F.Paste")
			(net "BMC_SSD_RST#10")
		)
		(pad "D18" smd circle
			(at 5.199888 -5.999988 180)
			(size 0.3556 0.3556)
			(layers "F.Cu" "F.Mask" "F.Paste")
			(net "BMC_SSD_RST#7")
		)
		(pad "D19" smd circle
			(at 5.999988 -5.999988 180)
			(size 0.3556 0.3556)
			(layers "F.Cu" "F.Mask" "F.Paste")
			(net "TP_GPIOI2")
		)
		(pad "D20" smd circle
			(at 6.800088 -5.999988 180)
			(size 0.3556 0.3556)
			(layers "F.Cu" "F.Mask" "F.Paste")
			(net "BMC_PEREXT")
		)
		(pad "D21" smd circle
			(at 7.599934 -5.999988 180)
			(size 0.3556 0.3556)
			(layers "F.Cu" "F.Mask" "F.Paste")
			(net "GND")
		)
		(pad "D22" smd circle
			(at 8.400034 -5.999988 180)
			(size 0.3556 0.3556)
			(layers "F.Cu" "F.Mask" "F.Paste")
			(net "GND")
		)
		(pad "E1" smd circle
			(at -8.400034 -5.199888 180)
			(size 0.3556 0.3556)
			(layers "F.Cu" "F.Mask" "F.Paste")
			(net "JTAG_BMC_TRST_N")
		)
		(pad "E2" smd circle
			(at -7.599934 -5.199888 180)
			(size 0.3556 0.3556)
			(layers "F.Cu" "F.Mask" "F.Paste")
			(net "BMC0_SMB7_CLK")
		)
		(pad "E3" smd circle
			(at -6.800088 -5.199888 180)
			(size 0.3556 0.3556)
			(layers "F.Cu" "F.Mask" "F.Paste")
			(net "BMC0_SMB5_CLK")
		)
		(pad "E4" smd circle
			(at -5.999988 -5.199888 180)
			(size 0.3556 0.3556)
			(layers "F.Cu" "F.Mask" "F.Paste")
			(net "BMC0_ENTEST1")
		)
		(pad "E5" smd circle
			(at -5.199888 -5.199888 180)
			(size 0.3556 0.3556)
			(layers "F.Cu" "F.Mask" "F.Paste")
			(net "BMC0_SDA11_R")
		)
		(pad "E6" smd circle
			(at -4.400042 -5.199888 180)
			(size 0.3556 0.3556)
			(layers "F.Cu" "F.Mask" "F.Paste")
			(net "TP_GPIOA3")
		)
		(pad "E7" smd circle
			(at -3.599942 -5.199888 180)
			(size 0.3556 0.3556)
			(layers "F.Cu" "F.Mask" "F.Paste")
			(net "TP_GPIOH7")
		)
		(pad "E8" smd circle
			(at -2.800096 -5.199888 180)
			(size 0.3556 0.3556)
			(layers "F.Cu" "F.Mask" "F.Paste")
			(net "TP_GPIOV5")
		)
		(pad "E9" smd circle
			(at -1.999996 -5.199888 180)
			(size 0.3556 0.3556)
			(layers "F.Cu" "F.Mask" "F.Paste")
			(net "TP_GPIOT7")
		)
		(pad "E10" smd circle
			(at -1.199896 -5.199888 180)
			(size 0.3556 0.3556)
			(layers "F.Cu" "F.Mask" "F.Paste")
			(net "RMII_BMC_RX_ER")
		)
		(pad "E11" smd circle
			(at -0.40005 -5.199888 180)
			(size 0.3556 0.3556)
			(layers "F.Cu" "F.Mask" "F.Paste")
			(net "BMC_RXCK_R")
		)
		(pad "E12" smd circle
			(at 0.40005 -5.199888 180)
			(size 0.3556 0.3556)
			(layers "F.Cu" "F.Mask" "F.Paste")
			(net "GND")
		)
		(pad "E13" smd circle
			(at 1.199896 -5.199888 180)
			(size 0.3556 0.3556)
			(layers "F.Cu" "F.Mask" "F.Paste")
			(net "HIGH_HEX_1")
		)
		(pad "E14" smd circle
			(at 1.999996 -5.199888 180)
			(size 0.3556 0.3556)
			(layers "F.Cu" "F.Mask" "F.Paste")
			(net "BMC_ADD1_R")
		)
		(pad "E15" smd circle
			(at 2.800096 -5.199888 180)
			(size 0.3556 0.3556)
			(layers "F.Cu" "F.Mask" "F.Paste")
			(net "TP_GPIOD7")
		)
		(pad "E16" smd circle
			(at 3.599942 -5.199888 180)
			(size 0.3556 0.3556)
			(layers "F.Cu" "F.Mask" "F.Paste")
			(net "BMC_SSD_RST#13")
		)
		(pad "E17" smd circle
			(at 4.400042 -5.199888 180)
			(size 0.3556 0.3556)
			(layers "F.Cu" "F.Mask" "F.Paste")
			(net "TP_IRQ_CPU_SERIAL")
		)
		(pad "E18" smd circle
			(at 5.199888 -5.199888 180)
			(size 0.3556 0.3556)
			(layers "F.Cu" "F.Mask" "F.Paste")
			(net "RST_BMC_EXTRST_N_R")
		)
		(pad "E19" smd circle
			(at 5.999988 -5.199888 180)
			(size 0.3556 0.3556)
			(layers "F.Cu" "F.Mask" "F.Paste")
			(net "FM_PCH_LAN1_DISABLE_N_R")
		)
		(pad "E20" smd circle
			(at 6.800088 -5.199888 180)
			(size 0.3556 0.3556)
			(layers "F.Cu" "F.Mask" "F.Paste")
			(net "SPIDI_R")
		)
		(pad "E21" smd circle
			(at 7.599934 -5.199888 180)
			(size 0.3556 0.3556)
			(layers "F.Cu" "F.Mask" "F.Paste")
			(net "BMC_PETXN")
		)
		(pad "E22" smd circle
			(at 8.400034 -5.199888 180)
			(size 0.3556 0.3556)
			(layers "F.Cu" "F.Mask" "F.Paste")
			(net "BMC_PETXP")
		)
		(pad "F1" smd circle
			(at -8.400034 -4.400042 180)
			(size 0.3556 0.3556)
			(layers "F.Cu" "F.Mask" "F.Paste")
			(net "JTAG_BMC_TDI")
		)
		(pad "F2" smd circle
			(at -7.599934 -4.400042 180)
			(size 0.3556 0.3556)
			(layers "F.Cu" "F.Mask" "F.Paste")
			(net "JTAG_BMC_TCK")
		)
		(pad "F3" smd circle
			(at -6.800088 -4.400042 180)
			(size 0.3556 0.3556)
			(layers "F.Cu" "F.Mask" "F.Paste")
			(net "BMC0_SMB8_DAT")
		)
		(pad "F4" smd circle
			(at -5.999988 -4.400042 180)
			(size 0.3556 0.3556)
			(layers "F.Cu" "F.Mask" "F.Paste")
			(net "BMC0_SMB6_DAT")
		)
		(pad "F5" smd circle
			(at -5.199888 -4.400042 180)
			(size 0.3556 0.3556)
			(layers "F.Cu" "F.Mask" "F.Paste")
			(net "BMC0_SMB4_DAT")
		)
		(pad "F8" smd circle
			(at -2.800096 -4.400042 180)
			(size 0.3556 0.3556)
			(layers "F.Cu" "F.Mask" "F.Paste")
			(net "P3V3_STBY")
		)
		(pad "F9" smd circle
			(at -1.999996 -4.400042 180)
			(size 0.3556 0.3556)
			(layers "F.Cu" "F.Mask" "F.Paste")
			(net "P3V3_STBY")
		)
		(pad "F10" smd circle
			(at -1.199896 -4.400042 180)
			(size 0.3556 0.3556)
			(layers "F.Cu" "F.Mask" "F.Paste")
			(net "P3V3_STBY")
		)
		(pad "F11" smd circle
			(at -0.40005 -4.400042 180)
			(size 0.3556 0.3556)
			(layers "F.Cu" "F.Mask" "F.Paste")
			(net "P3V3_STBY")
		)
		(pad "F12" smd circle
			(at 0.40005 -4.400042 180)
			(size 0.3556 0.3556)
			(layers "F.Cu" "F.Mask" "F.Paste")
			(net "P3V3_STBY")
		)
		(pad "F13" smd circle
			(at 1.199896 -4.400042 180)
			(size 0.3556 0.3556)
			(layers "F.Cu" "F.Mask" "F.Paste")
			(net "P3V3_STBY")
		)
		(pad "F14" smd circle
			(at 1.999996 -4.400042 180)
			(size 0.3556 0.3556)
			(layers "F.Cu" "F.Mask" "F.Paste")
			(net "P1V26_STBY")
		)
		(pad "F15" smd circle
			(at 2.800096 -4.400042 180)
			(size 0.3556 0.3556)
			(layers "F.Cu" "F.Mask" "F.Paste")
			(net "P1V26_STBY")
		)
		(pad "F18" smd circle
			(at 5.199888 -4.400042 180)
			(size 0.3556 0.3556)
			(layers "F.Cu" "F.Mask" "F.Paste")
			(net "LAN_SMB_ALERT_N_R")
		)
		(pad "F19" smd circle
			(at 5.999988 -4.400042 180)
			(size 0.3556 0.3556)
			(layers "F.Cu" "F.Mask" "F.Paste")
			(net "TP_BMC0_LPC_LAD2")
		)
		(pad "F20" smd circle
			(at 6.800088 -4.400042 180)
			(size 0.3556 0.3556)
			(layers "F.Cu" "F.Mask" "F.Paste")
			(net "FCB_HW_REVISION")
		)
		(pad "F21" smd circle
			(at 7.599934 -4.400042 180)
			(size 0.3556 0.3556)
			(layers "F.Cu" "F.Mask" "F.Paste")
			(net "PCIE_TX_P76")
		)
		(pad "F22" smd circle
			(at 8.400034 -4.400042 180)
			(size 0.3556 0.3556)
			(layers "F.Cu" "F.Mask" "F.Paste")
			(net "PCIE_TX_N76")
		)
		(pad "G1" smd circle
			(at -8.400034 -3.599942 180)
			(size 0.3556 0.3556)
			(layers "F.Cu" "F.Mask" "F.Paste")
			(net "BMC_RXD5_R")
		)
		(pad "G2" smd circle
			(at -7.599934 -3.599942 180)
			(size 0.3556 0.3556)
			(layers "F.Cu" "F.Mask" "F.Paste")
			(net "JTAG_BMC_TMS")
		)
		(pad "G3" smd circle
			(at -6.800088 -3.599942 180)
			(size 0.3556 0.3556)
			(layers "F.Cu" "F.Mask" "F.Paste")
			(net "JTAG_BMC_TDO")
		)
		(pad "G4" smd circle
			(at -5.999988 -3.599942 180)
			(size 0.3556 0.3556)
			(layers "F.Cu" "F.Mask" "F.Paste")
			(net "BMC0_JTAG_RTCK")
		)
		(pad "G5" smd circle
			(at -5.199888 -3.599942 180)
			(size 0.3556 0.3556)
			(layers "F.Cu" "F.Mask" "F.Paste")
			(net "BMC0_SMB8_CLK")
		)
		(pad "G18" smd circle
			(at 5.199888 -3.599942 180)
			(size 0.3556 0.3556)
			(layers "F.Cu" "F.Mask" "F.Paste")
			(net "TP_GPIOI1")
		)
		(pad "G19" smd circle
			(at 5.999988 -3.599942 180)
			(size 0.3556 0.3556)
			(layers "F.Cu" "F.Mask" "F.Paste")
			(net "SPICK_R")
		)
		(pad "G20" smd circle
			(at 6.800088 -3.599942 180)
			(size 0.3556 0.3556)
			(layers "F.Cu" "F.Mask" "F.Paste")
			(net "DPB_HW_REVISION")
		)
		(pad "G21" smd circle
			(at 7.599934 -3.599942 180)
			(size 0.3556 0.3556)
			(layers "F.Cu" "F.Mask" "F.Paste")
			(net "BMC_REFCLK_N")
		)
		(pad "G22" smd circle
			(at 8.400034 -3.599942 180)
			(size 0.3556 0.3556)
			(layers "F.Cu" "F.Mask" "F.Paste")
			(net "BMC_REFCLK_P")
		)
		(pad "H1" smd circle
			(at -8.400034 -2.800096 180)
			(size 0.3556 0.3556)
			(layers "F.Cu" "F.Mask" "F.Paste")
			(net "TCA9554_INT_N_R")
		)
		(pad "H2" smd circle
			(at -7.599934 -2.800096 180)
			(size 0.3556 0.3556)
			(layers "F.Cu" "F.Mask" "F.Paste")
			(net "I2C_MUX_RESET_PEB_R")
		)
		(pad "H3" smd circle
			(at -6.800088 -2.800096 180)
			(size 0.3556 0.3556)
			(layers "F.Cu" "F.Mask" "F.Paste")
			(net "BMC0_SMB14_SDA")
		)
		(pad "H4" smd circle
			(at -5.999988 -2.800096 180)
			(size 0.3556 0.3556)
			(layers "F.Cu" "F.Mask" "F.Paste")
			(net "BMC0_SMB14_CLK")
		)
		(pad "H5" smd circle
			(at -5.199888 -2.800096 180)
			(size 0.3556 0.3556)
			(layers "F.Cu" "F.Mask" "F.Paste")
			(net "BMC_TXD5_R")
		)
		(pad "H6" smd circle
			(at -4.400042 -2.800096 180)
			(size 0.3556 0.3556)
			(layers "F.Cu" "F.Mask" "F.Paste")
			(net "P3V3_STBY")
		)
		(pad "H17" smd circle
			(at 4.400042 -2.800096 180)
			(size 0.3556 0.3556)
			(layers "F.Cu" "F.Mask" "F.Paste")
			(net "P3V3_STBY")
		)
		(pad "H18" smd circle
			(at 5.199888 -2.800096 180)
			(size 0.3556 0.3556)
			(layers "F.Cu" "F.Mask" "F.Paste")
			(net "TP_GPIOB2")
		)
		(pad "H19" smd circle
			(at 5.999988 -2.800096 180)
			(size 0.3556 0.3556)
			(layers "F.Cu" "F.Mask" "F.Paste")
			(net "TP_GPIOB5")
		)
		(pad "H20" smd circle
			(at 6.800088 -2.800096 180)
			(size 0.3556 0.3556)
			(layers "F.Cu" "F.Mask" "F.Paste")
			(net "TP_GPIOB6")
		)
		(pad "H21" smd circle
			(at 7.599934 -2.800096 180)
			(size 0.3556 0.3556)
			(layers "F.Cu" "F.Mask" "F.Paste")
			(net "Net_2083")
		)
		(pad "H22" smd circle
			(at 8.400034 -2.800096 180)
			(size 0.3556 0.3556)
			(layers "F.Cu" "F.Mask" "F.Paste")
			(net "Net_2082")
		)
		(pad "J1" smd circle
			(at -8.400034 -1.999996 180)
			(size 0.3556 0.3556)
			(layers "F.Cu" "F.Mask" "F.Paste")
			(net "BMC_USB1_HDP")
		)
		(pad "J2" smd circle
			(at -7.599934 -1.999996 180)
			(size 0.3556 0.3556)
			(layers "F.Cu" "F.Mask" "F.Paste")
			(net "BMC_USB1_HDN")
		)
		(pad "J3" smd circle
			(at -6.800088 -1.999996 180)
			(size 0.3556 0.3556)
			(layers "F.Cu" "F.Mask" "F.Paste")
			(net "LOW_HEX_3")
		)
		(pad "J4" smd circle
			(at -5.999988 -1.999996 180)
			(size 0.3556 0.3556)
			(layers "F.Cu" "F.Mask" "F.Paste")
			(net "LOW_HEX_1")
		)
		(pad "J5" smd circle
			(at -5.199888 -1.999996 180)
			(size 0.3556 0.3556)
			(layers "F.Cu" "F.Mask" "F.Paste")
			(net "LOW_HEX_0")
		)
		(pad "J6" smd circle
			(at -4.400042 -1.999996 180)
			(size 0.3556 0.3556)
			(layers "F.Cu" "F.Mask" "F.Paste")
			(net "P3V3_STBY")
		)
		(pad "J9" smd circle
			(at -1.999996 -1.999996 180)
			(size 0.3556 0.3556)
			(layers "F.Cu" "F.Mask" "F.Paste")
			(net "GND")
		)
		(pad "J10" smd circle
			(at -1.199896 -1.999996 180)
			(size 0.3556 0.3556)
			(layers "F.Cu" "F.Mask" "F.Paste")
			(net "GND")
		)
		(pad "J11" smd circle
			(at -0.40005 -1.999996 180)
			(size 0.3556 0.3556)
			(layers "F.Cu" "F.Mask" "F.Paste")
			(net "GND")
		)
		(pad "J12" smd circle
			(at 0.40005 -1.999996 180)
			(size 0.3556 0.3556)
			(layers "F.Cu" "F.Mask" "F.Paste")
			(net "GND")
		)
		(pad "J13" smd circle
			(at 1.199896 -1.999996 180)
			(size 0.3556 0.3556)
			(layers "F.Cu" "F.Mask" "F.Paste")
			(net "GND")
		)
		(pad "J14" smd circle
			(at 1.999996 -1.999996 180)
			(size 0.3556 0.3556)
			(layers "F.Cu" "F.Mask" "F.Paste")
			(net "GND")
		)
		(pad "J17" smd circle
			(at 4.400042 -1.999996 180)
			(size 0.3556 0.3556)
			(layers "F.Cu" "F.Mask" "F.Paste")
			(net "P3V3_STBY")
		)
		(pad "J18" smd circle
			(at 5.199888 -1.999996 180)
			(size 0.3556 0.3556)
			(layers "F.Cu" "F.Mask" "F.Paste")
			(net "BMC0_SMB2_DAT")
		)
		(pad "J19" smd circle
			(at 5.999988 -1.999996 180)
			(size 0.3556 0.3556)
			(layers "F.Cu" "F.Mask" "F.Paste")
			(net "BMC0_SMB2_CLK")
		)
		(pad "J20" smd circle
			(at 6.800088 -1.999996 180)
			(size 0.3556 0.3556)
			(layers "F.Cu" "F.Mask" "F.Paste")
			(net "GPIOB1")
		)
		(pad "J21" smd circle
			(at 7.599934 -1.999996 180)
			(size 0.3556 0.3556)
			(layers "F.Cu" "F.Mask" "F.Paste")
			(net "PE1_PERST#_BMC")
		)
		(pad "J22" smd circle
			(at 8.400034 -1.999996 180)
			(size 0.3556 0.3556)
			(layers "F.Cu" "F.Mask" "F.Paste")
			(net "PEWAKE#")
		)
		(pad "K1" smd circle
			(at -8.400034 -1.199896 180)
			(size 0.3556 0.3556)
			(layers "F.Cu" "F.Mask" "F.Paste")
			(net "ADCVREFFP")
		)
		(pad "K2" smd circle
			(at -7.599934 -1.199896 180)
			(size 0.3556 0.3556)
			(layers "F.Cu" "F.Mask" "F.Paste")
			(net "ADCVREFFN")
		)
		(pad "K3" smd circle
			(at -6.800088 -1.199896 180)
			(size 0.3556 0.3556)
			(layers "F.Cu" "F.Mask" "F.Paste")
			(net "BMC_USB1_HDN2")
		)
		(pad "K4" smd circle
			(at -5.999988 -1.199896 180)
			(size 0.3556 0.3556)
			(layers "F.Cu" "F.Mask" "F.Paste")
			(net "BMC_USB1_HDP2")
		)
		(pad "K5" smd circle
			(at -5.199888 -1.199896 180)
			(size 0.3556 0.3556)
			(layers "F.Cu" "F.Mask" "F.Paste")
			(net "LOW_HEX_2")
		)
		(pad "K6" smd circle
			(at -4.400042 -1.199896 180)
			(size 0.3556 0.3556)
			(layers "F.Cu" "F.Mask" "F.Paste")
			(net "P1V26_STBY")
		)
		(pad "K9" smd circle
			(at -1.999996 -1.199896 180)
			(size 0.3556 0.3556)
			(layers "F.Cu" "F.Mask" "F.Paste")
			(net "GND")
		)
		(pad "K10" smd circle
			(at -1.199896 -1.199896 180)
			(size 0.3556 0.3556)
			(layers "F.Cu" "F.Mask" "F.Paste")
			(net "GND")
		)
		(pad "K11" smd circle
			(at -0.40005 -1.199896 180)
			(size 0.3556 0.3556)
			(layers "F.Cu" "F.Mask" "F.Paste")
			(net "GND")
		)
		(pad "K12" smd circle
			(at 0.40005 -1.199896 180)
			(size 0.3556 0.3556)
			(layers "F.Cu" "F.Mask" "F.Paste")
			(net "GND")
		)
		(pad "K13" smd circle
			(at 1.199896 -1.199896 180)
			(size 0.3556 0.3556)
			(layers "F.Cu" "F.Mask" "F.Paste")
			(net "GND")
		)
		(pad "K14" smd circle
			(at 1.999996 -1.199896 180)
			(size 0.3556 0.3556)
			(layers "F.Cu" "F.Mask" "F.Paste")
			(net "GND")
		)
		(pad "K17" smd circle
			(at 4.400042 -1.199896 180)
			(size 0.3556 0.3556)
			(layers "F.Cu" "F.Mask" "F.Paste")
			(net "P1V26_STBY")
		)
		(pad "K18" smd circle
			(at 5.199888 -1.199896 180)
			(size 0.3556 0.3556)
			(layers "F.Cu" "F.Mask" "F.Paste")
			(net "ROMA23")
		)
		(pad "K19" smd circle
			(at 5.999988 -1.199896 180)
			(size 0.3556 0.3556)
			(layers "F.Cu" "F.Mask" "F.Paste")
			(net "BMC_PERST#_R")
		)
	)
)
